# T6G (Grand Teton) — schematic netlist excerpt (pin names and nets, part order shuffled) for the footprints in the layout excerpt that follows; sources: Cadence DE-HDL packaged netlist, KiCad conversion of 04192023_DAF0TMB3IC0_F0TG_MB_C_brd_V02_OCP.brd

C6038  Q_CAP  0.1UF 25V 10% X7R  pkg 0402  page 177 : A = P1V2_CPU0_USB_DVDD12 ; B = GND
R1709  Q_RES  10 1% CHIP  pkg 0402LF  page 107 : A = I3C_SPD_DDRGL_CPU1_SDA ; B = I3C_SPD_DDRJ_CPU1_SDA

(kicad_pcb
	(version 20260206)
	(generator "pcbnew")
	(generator_version "10.0")
	(general
		(thickness 1.6)
		(legacy_teardrops no)
	)
	(paper "A4")
	(title_block
		(title "04192023_DAF0TMB3IC0_F0TG_MB_C_brd_V02_OCP.brd")
		(comment 1 "Grand Teton / footprints 7143-7144 of 8354")
	)
	(layers
		(0 "F.Cu" signal "TOP")
		(4 "In1.Cu" signal "GND")
		(6 "In2.Cu" signal "IN1")
		(8 "In3.Cu" signal "GND1")
		(10 "In4.Cu" signal "IN2")
		(12 "In5.Cu" signal "GND2")
		(14 "In6.Cu" signal "IN3")
		(16 "In7.Cu" signal "GND3")
		(18 "In8.Cu" signal "VCC")
		(20 "In9.Cu" signal "VCC1")
		(22 "In10.Cu" signal "GND4")
		(24 "In11.Cu" signal "IN4")
		(26 "In12.Cu" signal "GND5")
		(28 "In13.Cu" signal "IN5")
		(30 "In14.Cu" signal "GND6")
		(32 "In15.Cu" signal "IN6")
		(34 "In16.Cu" signal "GND7")
		(2 "B.Cu" signal "BOTTOM")
		(9 "F.Adhes" user "F.Adhesive")
		(11 "B.Adhes" user "B.Adhesive")
		(13 "F.Paste" user "Package Geometry/Pastemask Top")
		(15 "B.Paste" user "Package Geometry/Pastemask Bottom")
		(5 "F.SilkS" user "Ref Des/Silkscreen Top")
		(7 "B.SilkS" user "Ref Des/Silkscreen Bottom")
		(1 "F.Mask" user "Board Geometry/Soldermask Top")
		(3 "B.Mask" user "Board Geometry/Soldermask Bottom")
		(17 "Dwgs.User" user "User.Drawings")
		(19 "Cmts.User" user "User.Comments")
		(21 "Eco1.User" user "User.Eco1")
		(23 "Eco2.User" user "User.Eco2")
		(25 "Edge.Cuts" user "Board Geometry/Outline")
		(27 "Margin" user)
		(31 "F.CrtYd" user "Package Geometry/Place Bound Top")
		(29 "B.CrtYd" user "Package Geometry/Place Bound Bottom")
		(35 "F.Fab" user "Ref Des/Assembly Top")
		(33 "B.Fab" user "Ref Des/Assembly Bottom")
	)
	(footprint ""
		(layer "B.Cu")
		(at 190.404496 -195.8594 180)
		(property "Reference" "R1709"
			(at 0 0 0)
			(layer "B.SilkS")
			(hide yes)
			(effects
				(font
					(size 1.27 1.27)
				)
				(justify mirror)
			)
		)
		(property "Value" ""
			(at 0 0 0)
			(layer "B.Fab")
			(effects
				(font
					(size 1.27 1.27)
				)
				(justify mirror)
			)
		)
		(duplicate_pad_numbers_are_jumpers no)
		(fp_line
			(start 0.7874 0.4064)
			(end 0.7874 -0.4064)
			(stroke
				(width 0.1524)
				(type default)
			)
			(layer "B.SilkS")
		)
		(fp_line
			(start 0.7874 -0.4064)
			(end -0.7874 -0.4064)
			(stroke
				(width 0.1524)
				(type default)
			)
			(layer "B.SilkS")
		)
		(fp_line
			(start -0.7874 0.4064)
			(end 0.7874 0.4064)
			(stroke
				(width 0.1524)
				(type default)
			)
			(layer "B.SilkS")
		)
		(fp_line
			(start -0.7874 -0.4064)
			(end -0.7874 0.4064)
			(stroke
				(width 0.1524)
				(type default)
			)
			(layer "B.SilkS")
		)
		(fp_line
			(start 0.67945 0.3048)
			(end 0.67945 -0.305054)
			(stroke
				(width 0.1)
				(type default)
			)
			(layer "B.Fab")
		)
		(fp_line
			(start 0.67945 -0.305054)
			(end 0.12065 -0.305054)
			(stroke
				(width 0.1)
				(type default)
			)
			(layer "B.Fab")
		)
		(fp_line
			(start 0.12065 0.3048)
			(end 0.67945 0.3048)
			(stroke
				(width 0.1)
				(type default)
			)
			(layer "B.Fab")
		)
		(fp_line
			(start 0.12065 0.2794)
			(end 0.12065 0.3048)
			(stroke
				(width 0.1)
				(type default)
			)
			(layer "B.Fab")
		)
		(fp_line
			(start 0.12065 -0.2794)
			(end -0.12065 -0.2794)
			(stroke
				(width 0.1)
				(type default)
			)
			(layer "B.Fab")
		)
		(fp_line
			(start 0.12065 -0.305054)
			(end 0.12065 -0.2794)
			(stroke
				(width 0.1)
				(type default)
			)
			(layer "B.Fab")
		)
		(fp_line
			(start -0.120396 0.3048)
			(end -0.120396 0.2794)
			(stroke
				(width 0.1)
				(type default)
			)
			(layer "B.Fab")
		)
		(fp_line
			(start -0.120396 0.2794)
			(end 0.12065 0.2794)
			(stroke
				(width 0.1)
				(type default)
			)
			(layer "B.Fab")
		)
		(fp_line
			(start -0.12065 -0.2794)
			(end -0.12065 -0.3048)
			(stroke
				(width 0.1)
				(type default)
			)
			(layer "B.Fab")
		)
		(fp_line
			(start -0.12065 -0.3048)
			(end -0.67945 -0.3048)
			(stroke
				(width 0.1)
				(type default)
			)
			(layer "B.Fab")
		)
		(fp_line
			(start -0.67945 0.3048)
			(end -0.120396 0.3048)
			(stroke
				(width 0.1)
				(type default)
			)
			(layer "B.Fab")
		)
		(fp_line
			(start -0.67945 -0.3048)
			(end -0.67945 0.3048)
			(stroke
				(width 0.1)
				(type default)
			)
			(layer "B.Fab")
		)
		(pad "1" smd circle
			(at 0.40005 0)
			(size 0 0)
			(layers "B.Cu" "B.Mask" "B.Paste")
			(net "I3C_SPD_DDRGL_CPU1_SDA")
		)
		(pad "2" smd circle
			(at -0.40005 0)
			(size 0 0)
			(layers "B.Cu" "B.Mask" "B.Paste")
			(net "I3C_SPD_DDRJ_CPU1_SDA")
		)
	)
	(footprint ""
		(layer "B.Cu")
		(at 136.040114 -33.834578)
		(property "Reference" "C6038"
			(at 0 0 0)
			(layer "B.SilkS")
			(hide yes)
			(effects
				(font
					(size 1.27 1.27)
				)
				(justify mirror)
			)
		)
		(property "Value" ""
			(at 0 0 0)
			(layer "B.Fab")
			(effects
				(font
					(size 1.27 1.27)
				)
				(justify mirror)
			)
		)
		(duplicate_pad_numbers_are_jumpers no)
		(fp_line
			(start -0.7874 -0.4064)
			(end -0.7874 0.4064)
			(stroke
				(width 0.1524)
				(type default)
			)
			(layer "B.SilkS")
		)
		(fp_line
			(start -0.7874 0.4064)
			(end 0.7874 0.4064)
			(stroke
				(width 0.1524)
				(type default)
			)
			(layer "B.SilkS")
		)
		(fp_line
			(start 0.7874 -0.4064)
			(end -0.7874 -0.4064)
			(stroke
				(width 0.1524)
				(type default)
			)
			(layer "B.SilkS")
		)
		(fp_line
			(start 0.7874 0.4064)
			(end 0.7874 -0.4064)
			(stroke
				(width 0.1524)
				(type default)
			)
			(layer "B.SilkS")
		)
		(fp_line
			(start -0.67945 -0.3048)
			(end -0.67945 0.3048)
			(stroke
				(width 0.1)
				(type default)
			)
			(layer "B.Fab")
		)
		(fp_line
			(start -0.67945 0.3048)
			(end -0.120396 0.3048)
			(stroke
				(width 0.1)
				(type default)
			)
			(layer "B.Fab")
		)
		(fp_line
			(start -0.12065 -0.3048)
			(end -0.67945 -0.3048)
			(stroke
				(width 0.1)
				(type default)
			)
			(layer "B.Fab")
		)
		(fp_line
			(start -0.12065 -0.2794)
			(end -0.12065 -0.3048)
			(stroke
				(width 0.1)
				(type default)
			)
			(layer "B.Fab")
		)
		(fp_line
			(start -0.120396 0.2794)
			(end 0.12065 0.2794)
			(stroke
				(width 0.1)
				(type default)
			)
			(layer "B.Fab")
		)
		(fp_line
			(start -0.120396 0.3048)
			(end -0.120396 0.2794)
			(stroke
				(width 0.1)
				(type default)
			)
			(layer "B.Fab")
		)
		(fp_line
			(start 0.12065 -0.305054)
			(end 0.12065 -0.2794)
			(stroke
				(width 0.1)
				(type default)
			)
			(layer "B.Fab")
		)
		(fp_line
			(start 0.12065 -0.2794)
			(end -0.12065 -0.2794)
			(stroke
				(width 0.1)
				(type default)
			)
			(layer "B.Fab")
		)
		(fp_line
			(start 0.12065 0.2794)
			(end 0.12065 0.3048)
			(stroke
				(width 0.1)
				(type default)
			)
			(layer "B.Fab")
		)
		(fp_line
			(start 0.12065 0.3048)
			(end 0.67945 0.3048)
			(stroke
				(width 0.1)
				(type default)
			)
			(layer "B.Fab")
		)
		(fp_line
			(start 0.67945 -0.305054)
			(end 0.12065 -0.305054)
			(stroke
				(width 0.1)
				(type default)
			)
			(layer "B.Fab")
		)
		(fp_line
			(start 0.67945 0.3048)
			(end 0.67945 -0.305054)
			(stroke
				(width 0.1)
				(type default)
			)
			(layer "B.Fab")
		)
		(pad "1" smd circle
			(at 0.40005 0 180)
			(size 0 0)
			(layers "B.Cu" "B.Mask" "B.Paste")
			(net "P1V2_CPU0_USB_DVDD12")
		)
		(pad "2" smd circle
			(at -0.40005 0 180)
			(size 0 0)
			(layers "B.Cu" "B.Mask" "B.Paste")
			(net "GND")
		)
	)
)
